(kicad_pcb
	(version 20241229)
	(generator "pcbnew")
	(generator_version "9.0")
	(general
		(thickness 1.61)
		(legacy_teardrops no)
	)
	(paper "A3")
	(title_block
		(title "RDIMM DDR5 Tester")
		(date "2026-05-21")
		(rev "2.2.0")
		(company "Antmicro")
		(comment 9 "footprints 280-284 of 796")
	)
	(layers
		(0 "F.Cu" signal)
		(4 "In1.Cu" power)
		(6 "In2.Cu" mixed)
		(8 "In3.Cu" power)
		(10 "In4.Cu" mixed)
		(12 "In5.Cu" power)
		(14 "In6.Cu" mixed)
		(16 "In7.Cu" power)
		(18 "In8.Cu" power)
		(20 "In9.Cu" mixed)
		(22 "In10.Cu" power)
		(2 "B.Cu" signal)
		(9 "F.Adhes" user "F.Adhesive")
		(11 "B.Adhes" user "B.Adhesive")
		(13 "F.Paste" user)
		(15 "B.Paste" user)
		(5 "F.SilkS" user "F.Silkscreen")
		(7 "B.SilkS" user "B.Silkscreen")
		(1 "F.Mask" user)
		(3 "B.Mask" user)
		(17 "Dwgs.User" user "User.Drawings")
		(19 "Cmts.User" user "User.Comments")
		(21 "Eco1.User" user "User.Eco1")
		(23 "Eco2.User" user "User.Eco2")
		(25 "Edge.Cuts" user)
		(27 "Margin" user)
		(31 "F.CrtYd" user "F.Courtyard")
		(29 "B.CrtYd" user "B.Courtyard")
		(35 "F.Fab" user)
		(33 "B.Fab" user)
	)
	(footprint "antmicro-footprints:C_0402_1005Metric"
		(layer "F.Cu")
		(at 128.306 176.022 -90)
		(descr "Capacitor SMD 0402")
		(tags "capacitor SMD 0402")
		(property "Reference" "C277"
			(at -4.05 -0.49 90)
			(layer "F.SilkS")
			(effects
				(font
					(size 0.7 0.7)
					(thickness 0.15)
				)
				(justify right bottom)
			)
		)
		(property "Value" "C_10u_10V_0402"
			(at -1.022927 2.155213 90)
			(layer "F.Fab")
			(effects
				(font
					(size 0.7 0.7)
					(thickness 0.15)
				)
				(justify right bottom)
			)
		)
		(property "Datasheet" "https://www.murata.com/products/productdetail?partno=GRM155R61A106ME11%23"
			(at 0 0 270)
			(layer "F.Fab")
			(hide yes)
			(effects
				(font
					(size 1.27 1.27)
					(thickness 0.15)
				)
			)
		)
		(property "MPN" "GRM155R61A106ME11D"
			(at 0 0 270)
			(unlocked yes)
			(layer "F.Fab")
			(hide yes)
			(effects
				(font
					(size 1 1)
					(thickness 0.15)
				)
			)
		)
		(property "Manufacturer" "Murata"
			(at 0 0 270)
			(unlocked yes)
			(layer "F.Fab")
			(hide yes)
			(effects
				(font
					(size 1 1)
					(thickness 0.15)
				)
			)
		)
		(property "License" "Apache-2.0"
			(at 0 0 270)
			(unlocked yes)
			(layer "F.Fab")
			(hide yes)
			(effects
				(font
					(size 1 1)
					(thickness 0.15)
				)
			)
		)
		(property "Author" "Antmicro"
			(at 0 0 270)
			(unlocked yes)
			(layer "F.Fab")
			(hide yes)
			(effects
				(font
					(size 1 1)
					(thickness 0.15)
				)
			)
		)
		(property "Val" "10u"
			(at 0 0 270)
			(unlocked yes)
			(layer "F.Fab")
			(hide yes)
			(effects
				(font
					(size 1 1)
					(thickness 0.15)
				)
			)
		)
		(property "Voltage" "10V"
			(at 0 0 270)
			(unlocked yes)
			(layer "F.Fab")
			(hide yes)
			(effects
				(font
					(size 1 1)
					(thickness 0.15)
				)
			)
		)
		(property "Dielectric" "X5R"
			(at 0 0 270)
			(unlocked yes)
			(layer "F.Fab")
			(hide yes)
			(effects
				(font
					(size 1 1)
					(thickness 0.15)
				)
			)
		)
		(property "Public" ""
			(at 0 0 270)
			(unlocked yes)
			(layer "F.Fab")
			(hide yes)
			(effects
				(font
					(size 1 1)
					(thickness 0.15)
				)
			)
		)
		(sheetname "/HDMI + SD Card/")
		(sheetfile "hdmi-sd-card.kicad_sch")
		(attr smd)
		(fp_rect
			(start -0.925 -0.47)
			(end 0.925 0.47)
			(stroke
				(width 0.05)
				(type default)
			)
			(fill no)
			(layer "F.CrtYd")
		)
		(fp_line
			(start -0.494 0.248)
			(end -0.494 -0.25)
			(stroke
				(width 0.15)
				(type solid)
			)
			(layer "F.Fab")
		)
		(fp_line
			(start 0.504 0.248)
			(end -0.494 0.248)
			(stroke
				(width 0.15)
				(type solid)
			)
			(layer "F.Fab")
		)
		(fp_line
			(start -0.494 -0.25)
			(end 0.504 -0.25)
			(stroke
				(width 0.15)
				(type solid)
			)
			(layer "F.Fab")
		)
		(fp_line
			(start 0.504 -0.25)
			(end 0.504 0.248)
			(stroke
				(width 0.15)
				(type solid)
			)
			(layer "F.Fab")
		)
		(fp_text user "${REFERENCE}"
			(at -0.939 4.599 270)
			(layer "F.Fab")
			(effects
				(font
					(size 0.7 0.7)
					(thickness 0.15)
				)
				(justify left bottom)
			)
		)
		(fp_text user "License: Apache-2.0"
			(at -0.939 5.799 270)
			(layer "F.Fab")
			(effects
				(font
					(size 0.7 0.7)
					(thickness 0.15)
				)
				(justify left bottom)
			)
		)
		(fp_text user "Author: Antmicro"
			(at -0.939 3.399 270)
			(layer "F.Fab")
			(effects
				(font
					(size 0.7 0.7)
					(thickness 0.15)
				)
				(justify left bottom)
			)
		)
		(pad "1" smd roundrect
			(at -0.48 0 270)
			(size 0.59 0.64)
			(layers "F.Cu" "F.Mask" "F.Paste")
			(roundrect_rratio 0.25)
			(net 1 "GND")
			(pintype "passive")
		)
		(pad "2" smd roundrect
			(at 0.48 0 270)
			(size 0.59 0.64)
			(layers "F.Cu" "F.Mask" "F.Paste")
			(roundrect_rratio 0.25)
			(net 151 "+3V3")
			(pintype "passive")
		)
	)
	(footprint "antmicro-footprints:SOT-23-5"
		(layer "F.Cu")
		(at 239.274499 164.4)
		(property "Reference" "U29"
			(at -1.047499 3.025 0)
			(layer "F.SilkS")
			(effects
				(font
					(size 0.7 0.7)
					(thickness 0.15)
				)
				(justify left bottom)
			)
		)
		(property "Value" "AT24CS01_SOT23"
			(at 0.002 2.799 0)
			(layer "F.Fab")
			(effects
				(font
					(size 0.7 0.7)
					(thickness 0.15)
				)
				(justify left bottom)
			)
		)
		(property "Datasheet" "http://ww1.microchip.com/downloads/en/devicedoc/Atmel-8815-SEEPROM-AT24CS01-02-Datasheet.pdf"
			(at 0 0 0)
			(layer "F.Fab")
			(hide yes)
			(effects
				(font
					(size 1.27 1.27)
					(thickness 0.15)
				)
			)
		)
		(property "Manufacturer" "Atmel"
			(at 0 0 0)
			(unlocked yes)
			(layer "F.Fab")
			(hide yes)
			(effects
				(font
					(size 1 1)
					(thickness 0.15)
				)
			)
		)
		(property "MPN" "AT24CS01-ST"
			(at 0 0 0)
			(unlocked yes)
			(layer "F.Fab")
			(hide yes)
			(effects
				(font
					(size 1 1)
					(thickness 0.15)
				)
			)
		)
		(property "Author" "Antmicro"
			(at 0 0 0)
			(unlocked yes)
			(layer "F.Fab")
			(hide yes)
			(effects
				(font
					(size 1 1)
					(thickness 0.15)
				)
			)
		)
		(property "License" "Apache-2.0"
			(at 0 0 0)
			(unlocked yes)
			(layer "F.Fab")
			(hide yes)
			(effects
				(font
					(size 1 1)
					(thickness 0.15)
				)
			)
		)
		(sheetname "/Supply/")
		(sheetfile "supply.kicad_sch")
		(attr smd)
		(fp_line
			(start -0.85 1.6)
			(end -0.85 1.301)
			(stroke
				(width 0.15)
				(type solid)
			)
			(layer "F.SilkS")
		)
		(fp_line
			(start -0.8 -1.6)
			(end -0.8 -1.3)
			(stroke
				(width 0.15)
				(type solid)
			)
			(layer "F.SilkS")
		)
		(fp_line
			(start -0.8 -1.6)
			(end -0.5 -1.6)
			(stroke
				(width 0.15)
				(type solid)
			)
			(layer "F.SilkS")
		)
		(fp_line
			(start -0.55 1.6)
			(end -0.85 1.6)
			(stroke
				(width 0.15)
				(type solid)
			)
			(layer "F.SilkS")
		)
		(fp_line
			(start 0.8 -1.6)
			(end 0.5 -1.6)
			(stroke
				(width 0.15)
				(type solid)
			)
			(layer "F.SilkS")
		)
		(fp_line
			(start 0.8 -1.3)
			(end 0.8 -1.6)
			(stroke
				(width 0.15)
				(type solid)
			)
			(layer "F.SilkS")
		)
		(fp_line
			(start 0.8 0.55)
			(end 0.8 -0.55)
			(stroke
				(width 0.15)
				(type solid)
			)
			(layer "F.SilkS")
		)
		(fp_line
			(start 0.8 1.3)
			(end 0.8 1.599)
			(stroke
				(width 0.15)
				(type solid)
			)
			(layer "F.SilkS")
		)
		(fp_line
			(start 0.8 1.599)
			(end 0.549 1.599)
			(stroke
				(width 0.15)
				(type solid)
			)
			(layer "F.SilkS")
		)
		(fp_circle
			(center -1.25 -1.5)
			(end -1.2 -1.5)
			(stroke
				(width 0.15)
				(type solid)
			)
			(fill yes)
			(layer "F.SilkS")
		)
		(fp_rect
			(start 1.9 -1.76)
			(end -1.9 1.75)
			(stroke
				(width 0.05)
				(type solid)
			)
			(fill no)
			(layer "F.CrtYd")
		)
		(fp_line
			(start -0.398 -1.526)
			(end -0.874 -1.05)
			(stroke
				(width 0.15)
				(type solid)
			)
			(layer "F.Fab")
		)
		(fp_rect
			(start 0.874 1.523)
			(end -0.873 -1.525)
			(stroke
				(width 0.15)
				(type solid)
			)
			(fill no)
			(layer "F.Fab")
		)
		(fp_text user "${REFERENCE}"
			(at -1.898 4.299 0)
			(layer "F.Fab")
			(effects
				(font
					(size 0.7 0.7)
					(thickness 0.15)
				)
				(justify left bottom)
			)
		)
		(fp_text user "License: Apache-2.0"
			(at -1.898 6.7 0)
			(layer "F.Fab")
			(effects
				(font
					(size 0.7 0.7)
					(thickness 0.15)
				)
				(justify left bottom)
			)
		)
		(fp_text user "Author: Antmicro"
			(at -1.898 5.499 0)
			(layer "F.Fab")
			(effects
				(font
					(size 0.7 0.7)
					(thickness 0.15)
				)
				(justify left bottom)
			)
		)
		(pad "1" smd rect
			(at -1.351 -0.951 270)
			(size 0.55 1)
			(layers "F.Cu" "F.Mask" "F.Paste")
			(net 749 "/I^{2}C + I3C/PWR.SCL")
			(pinfunction "SCL")
			(pintype "passive")
		)
		(pad "2" smd rect
			(at -1.351 0 270)
			(size 0.55 1)
			(layers "F.Cu" "F.Mask" "F.Paste")
			(net 1 "GND")
			(pinfunction "GND")
			(pintype "passive")
		)
		(pad "3" smd rect
			(at -1.351 0.949 270)
			(size 0.55 1)
			(layers "F.Cu" "F.Mask" "F.Paste")
			(net 533 "/I^{2}C + I3C/PWR.SDA")
			(pinfunction "SDA")
			(pintype "passive")
		)
		(pad "4" smd rect
			(at 1.35 0.949 270)
			(size 0.55 1)
			(layers "F.Cu" "F.Mask" "F.Paste")
			(net 38 "+3V3_AON")
			(pinfunction "VCC")
			(pintype "passive")
		)
		(pad "5" smd rect
			(at 1.35 -0.951 270)
			(size 0.55 1)
			(layers "F.Cu" "F.Mask" "F.Paste")
			(net 1 "GND")
			(pinfunction "WP")
			(pintype "passive")
		)
	)
	(footprint "antmicro-footprints:R_0402_1005Metric"
		(layer "F.Cu")
		(at 158.25 166.124999)
		(descr "Resistor SMD 0402")
		(tags "resistor SMD 0402")
		(property "Reference" "R74"
			(at -1.02 1.515001 0)
			(layer "F.SilkS")
			(effects
				(font
					(size 0.7 0.7)
					(thickness 0.15)
				)
				(justify left bottom)
			)
		)
		(property "Value" "R_4k7_0402"
			(at -1.011843 1.772047 0)
			(layer "F.Fab")
			(effects
				(font
					(size 0.7 0.7)
					(thickness 0.15)
				)
				(justify left bottom)
			)
		)
		(property "Datasheet" "https://www.bourns.com/docs/product-datasheets/cr.pdf"
			(at 0 0 0)
			(layer "F.Fab")
			(hide yes)
			(effects
				(font
					(size 1.27 1.27)
					(thickness 0.15)
				)
			)
		)
		(property "MPN" "CR0402-FX-4701GLF"
			(at 0 0 0)
			(unlocked yes)
			(layer "F.Fab")
			(hide yes)
			(effects
				(font
					(size 1 1)
					(thickness 0.15)
				)
			)
		)
		(property "Manufacturer" "Bourns"
			(at 0 0 0)
			(unlocked yes)
			(layer "F.Fab")
			(hide yes)
			(effects
				(font
					(size 1 1)
					(thickness 0.15)
				)
			)
		)
		(property "License" "Apache-2.0"
			(at 0 0 0)
			(unlocked yes)
			(layer "F.Fab")
			(hide yes)
			(effects
				(font
					(size 1 1)
					(thickness 0.15)
				)
			)
		)
		(property "Author" "Antmicro"
			(at 0 0 0)
			(unlocked yes)
			(layer "F.Fab")
			(hide yes)
			(effects
				(font
					(size 1 1)
					(thickness 0.15)
				)
			)
		)
		(property "Val" "4k7"
			(at 0 0 0)
			(unlocked yes)
			(layer "F.Fab")
			(hide yes)
			(effects
				(font
					(size 1 1)
					(thickness 0.15)
				)
			)
		)
		(property "Tolerance" "1%"
			(at 0 0 0)
			(unlocked yes)
			(layer "F.Fab")
			(hide yes)
			(effects
				(font
					(size 1 1)
					(thickness 0.15)
				)
			)
		)
		(sheetname "/FPGA MGT Interface/")
		(sheetfile "fpga-mgt.kicad_sch")
		(attr smd)
		(fp_rect
			(start -0.925 -0.47)
			(end 0.925 0.47)
			(stroke
				(width 0.05)
				(type default)
			)
			(fill no)
			(layer "F.CrtYd")
		)
		(fp_rect
			(start -0.5 -0.25)
			(end 0.5 0.25)
			(stroke
				(width 0.15)
				(type solid)
			)
			(fill no)
			(layer "F.Fab")
		)
		(fp_text user "${REFERENCE}"
			(at -0.95 3.168 0)
			(layer "F.Fab")
			(effects
				(font
					(size 0.7 0.7)
					(thickness 0.15)
				)
				(justify left bottom)
			)
		)
		(fp_text user "License: Apache-2.0"
			(at -0.95 5.169 0)
			(layer "F.Fab")
			(effects
				(font
					(size 0.7 0.7)
					(thickness 0.15)
				)
				(justify left bottom)
			)
		)
		(fp_text user "Author: Antmicro"
			(at -0.95 4.169 0)
			(layer "F.Fab")
			(effects
				(font
					(size 0.7 0.7)
					(thickness 0.15)
				)
				(justify left bottom)
			)
		)
		(pad "1" smd roundrect
			(at -0.48 0)
			(size 0.59 0.64)
			(layers "F.Cu" "F.Mask" "F.Paste")
			(roundrect_rratio 0.25)
			(net 1 "GND")
			(pintype "passive")
		)
		(pad "2" smd roundrect
			(at 0.48 0)
			(size 0.59 0.64)
			(layers "F.Cu" "F.Mask" "F.Paste")
			(roundrect_rratio 0.25)
			(net 708 "Net-(U39-CS)")
			(pintype "passive")
		)
	)
	(footprint "antmicro-footprints:C_0402_1005Metric"
		(layer "F.Cu")
		(at 233.465001 178.791 90)
		(descr "Capacitor SMD 0402")
		(tags "capacitor SMD 0402")
		(property "Reference" "C216"
			(at -2.065 1.764999 90)
			(layer "F.SilkS")
			(effects
				(font
					(size 0.7 0.7)
					(thickness 0.15)
				)
				(justify left bottom)
			)
		)
		(property "Value" "C_220n_16V_0402"
			(at -1.022927 2.155213 90)
			(layer "F.Fab")
			(effects
				(font
					(size 0.7 0.7)
					(thickness 0.15)
				)
				(justify left bottom)
			)
		)
		(property "Datasheet" "https://www.murata.com/products/productdetail?partno=GRM155R71C224KA12%23"
			(at 0 0 90)
			(layer "F.Fab")
			(hide yes)
			(effects
				(font
					(size 1.27 1.27)
					(thickness 0.15)
				)
			)
		)
		(property "MPN" "GRM155R71C224KA12D"
			(at 0 0 90)
			(unlocked yes)
			(layer "F.Fab")
			(hide yes)
			(effects
				(font
					(size 1 1)
					(thickness 0.15)
				)
			)
		)
		(property "Manufacturer" "Murata"
			(at 0 0 90)
			(unlocked yes)
			(layer "F.Fab")
			(hide yes)
			(effects
				(font
					(size 1 1)
					(thickness 0.15)
				)
			)
		)
		(property "License" "Apache-2.0"
			(at 0 0 90)
			(unlocked yes)
			(layer "F.Fab")
			(hide yes)
			(effects
				(font
					(size 1 1)
					(thickness 0.15)
				)
			)
		)
		(property "Author" "Antmicro"
			(at 0 0 90)
			(unlocked yes)
			(layer "F.Fab")
			(hide yes)
			(effects
				(font
					(size 1 1)
					(thickness 0.15)
				)
			)
		)
		(property "Val" "220n"
			(at 0 0 90)
			(unlocked yes)
			(layer "F.Fab")
			(hide yes)
			(effects
				(font
					(size 1 1)
					(thickness 0.15)
				)
			)
		)
		(property "Voltage" "16V"
			(at 0 0 90)
			(unlocked yes)
			(layer "F.Fab")
			(hide yes)
			(effects
				(font
					(size 1 1)
					(thickness 0.15)
				)
			)
		)
		(property "Dielectric" "X7R"
			(at 0 0 90)
			(unlocked yes)
			(layer "F.Fab")
			(hide yes)
			(effects
				(font
					(size 1 1)
					(thickness 0.15)
				)
			)
		)
		(sheetname "/Supply/DC-DC VCCINT/")
		(sheetfile "dc-dc-vccint.kicad_sch")
		(attr smd)
		(fp_rect
			(start -0.925 -0.47)
			(end 0.925 0.47)
			(stroke
				(width 0.05)
				(type default)
			)
			(fill no)
			(layer "F.CrtYd")
		)
		(fp_line
			(start 0.504 -0.25)
			(end 0.504 0.248)
			(stroke
				(width 0.15)
				(type solid)
			)
			(layer "F.Fab")
		)
		(fp_line
			(start -0.494 -0.25)
			(end 0.504 -0.25)
			(stroke
				(width 0.15)
				(type solid)
			)
			(layer "F.Fab")
		)
		(fp_line
			(start 0.504 0.248)
			(end -0.494 0.248)
			(stroke
				(width 0.15)
				(type solid)
			)
			(layer "F.Fab")
		)
		(fp_line
			(start -0.494 0.248)
			(end -0.494 -0.25)
			(stroke
				(width 0.15)
				(type solid)
			)
			(layer "F.Fab")
		)
		(fp_text user "Author: Antmicro"
			(at -0.939 3.399 90)
			(layer "F.Fab")
			(effects
				(font
					(size 0.7 0.7)
					(thickness 0.15)
				)
				(justify left bottom)
			)
		)
		(fp_text user "License: Apache-2.0"
			(at -0.939 5.799 90)
			(layer "F.Fab")
			(effects
				(font
					(size 0.7 0.7)
					(thickness 0.15)
				)
				(justify left bottom)
			)
		)
		(fp_text user "${REFERENCE}"
			(at -0.939 4.599 90)
			(layer "F.Fab")
			(effects
				(font
					(size 0.7 0.7)
					(thickness 0.15)
				)
				(justify left bottom)
			)
		)
		(pad "1" smd roundrect
			(at -0.48 0 90)
			(size 0.59 0.64)
			(layers "F.Cu" "F.Mask" "F.Paste")
			(roundrect_rratio 0.25)
			(net 167 "Net-(U36-BST)")
			(pintype "passive")
		)
		(pad "2" smd roundrect
			(at 0.48 0 90)
			(size 0.59 0.64)
			(layers "F.Cu" "F.Mask" "F.Paste")
			(roundrect_rratio 0.25)
			(net 207 "Net-(C216-Pad2)")
			(pintype "passive")
		)
	)
	(footprint "antmicro-footprints:R_0805_2012Metric"
		(layer "F.Cu")
		(at 246.299499 167.948 180)
		(property "Reference" "R142"
			(at 0.899499 -1.852 180)
			(layer "F.SilkS")
			(effects
				(font
					(size 0.7 0.7)
					(thickness 0.15)
				)
				(justify left bottom)
			)
		)
		(property "Value" "R_0R002_0805"
			(at 0 1.8 180)
			(layer "F.Fab")
			(effects
				(font
					(size 0.7 0.7)
					(thickness 0.15)
				)
				(justify left bottom)
			)
		)
		(property "Datasheet" "https://www2.mouser.com/datasheet/2/447/PYu_PA0100_2512_51_RoHS_2-2604383.pdf"
			(at 0 0 180)
			(layer "F.Fab")
			(hide yes)
			(effects
				(font
					(size 1.27 1.27)
					(thickness 0.15)
				)
			)
		)
		(property "MPN" "PA0805FRE470R002L"
			(at 0 0 180)
			(unlocked yes)
			(layer "F.Fab")
			(hide yes)
			(effects
				(font
					(size 1 1)
					(thickness 0.15)
				)
			)
		)
		(property "Manufacturer" "YAGEO"
			(at 0 0 180)
			(unlocked yes)
			(layer "F.Fab")
			(hide yes)
			(effects
				(font
					(size 1 1)
					(thickness 0.15)
				)
			)
		)
		(property "License" "Apache-2.0"
			(at 0 0 180)
			(unlocked yes)
			(layer "F.Fab")
			(hide yes)
			(effects
				(font
					(size 1 1)
					(thickness 0.15)
				)
			)
		)
		(property "Author" "Antmicro"
			(at 0 0 180)
			(unlocked yes)
			(layer "F.Fab")
			(hide yes)
			(effects
				(font
					(size 1 1)
					(thickness 0.15)
				)
			)
		)
		(property "Val" "0R002"
			(at 0 0 180)
			(unlocked yes)
			(layer "F.Fab")
			(hide yes)
			(effects
				(font
					(size 1 1)
					(thickness 0.15)
				)
			)
		)
		(property "Tolerance" "1%"
			(at 0 0 180)
			(unlocked yes)
			(layer "F.Fab")
			(hide yes)
			(effects
				(font
					(size 1 1)
					(thickness 0.15)
				)
			)
		)
		(sheetname "/Supply/DC-DC AUX, MGT/")
		(sheetfile "dc-dc-aux-mgt.kicad_sch")
		(attr smd)
		(fp_line
			(start -0.3 -0.701)
			(end 0.298 -0.701)
			(stroke
				(width 0.15)
				(type solid)
			)
			(layer "F.SilkS")
		)
		(fp_line
			(start -0.32 0.699)
			(end 0.28 0.699)
			(stroke
				(width 0.15)
				(type solid)
			)
			(layer "F.SilkS")
		)
		(fp_rect
			(start 1.95 -0.9)
			(end -1.95 0.9)
			(stroke
				(width 0.05)
				(type default)
			)
			(fill no)
			(layer "F.CrtYd")
		)
		(fp_line
			(start 0.949 -0.677)
			(end 0.949 0.675)
			(stroke
				(width 0.15)
				(type solid)
			)
			(layer "F.Fab")
		)
		(fp_line
			(start -0.951 0.68)
			(end 0.949 0.68)
			(stroke
				(width 0.15)
				(type solid)
			)
			(layer "F.Fab")
		)
		(fp_line
			(start -0.951 -0.677)
			(end -0.951 0.675)
			(stroke
				(width 0.15)
				(type solid)
			)
			(layer "F.Fab")
		)
		(fp_line
			(start -0.951 -0.682)
			(end 0.949 -0.682)
			(stroke
				(width 0.15)
				(type solid)
			)
			(layer "F.Fab")
		)
		(fp_text user "License: Apache-2.0"
			(at -1.9 5.75 180)
			(layer "F.Fab")
			(effects
				(font
					(size 0.7 0.7)
					(thickness 0.15)
				)
				(justify left bottom)
			)
		)
		(fp_text user "Author: Antmicro"
			(at -1.9 4.4 180)
			(layer "F.Fab")
			(effects
				(font
					(size 0.7 0.7)
					(thickness 0.15)
				)
				(justify left bottom)
			)
		)
		(fp_text user "${REFERENCE}"
			(at -1.9 3.1 180)
			(layer "F.Fab")
			(effects
				(font
					(size 0.7 0.7)
					(thickness 0.15)
				)
				(justify left bottom)
			)
		)
		(pad "1" smd roundrect
			(at -1.1 0 180)
			(size 1.2 1.3)
			(layers "F.Cu" "F.Mask" "F.Paste")
			(roundrect_rratio 0.25)
			(net 48 "/Supply/DC-DC AUX, MGT/MGTAVTT_local")
			(pintype "passive")
		)
		(pad "2" smd roundrect
			(at 1.1 0 180)
			(size 1.2 1.3)
			(layers "F.Cu" "F.Mask" "F.Paste")
			(roundrect_rratio 0.25)
			(net 172 "+1V2_MGTAVTT")
			(pintype "passive")
		)
	)
)
